FILE_TYPE = CONNECTIVITY;
{Allegro Design Entry HDL 17.2-2016 S081 (4005846) 1/11/2022}
"PAGE_NUMBER" = 11;
0"NC";
1"P3V3_AUX\g";
2"P3V3_AUX\g";
3"P3V3_RGM\g";
4"GND\g";
5"GND\g";
6"FM_VIRTUAL_RESEAT";
7"PWRGD_SYS_PWROK";
8"PWRGD_PSU_AC_PWROK";
9"SGPIO_CLK_0";
10"SGPIO_CLK_1";
11"RST_PCA9548_SENSOR_N";
12"PWR_BTN_BMC_N";
13"RST_ROT_CPU_N";
14"SGPIO_DO_1";
15"SGPIO_DI_1";
16"SGPIO_LD_1";
17"SGPIO_DO_0";
18"SGPIO_DI_0";
19"SGPIO_LD_0";
20"IRQ_SGPIO_N";
21"RST_SGPIO_RESET_N";
22"RMII_CSRDV";
23"RMII_TXEN";
24"RMII_RXER";
25"FM_CPU_MSMI_CATERR_LVT3_N";
26"FM_THROTTLE_N";
27"SYS_PWRBTN_N";
28"LPC_ESPI_SEL";
29"RST_PLTRST_N";
%"VCCAUX15"
"1","(1975,6625)","0","logical_power","I101";
;
HDL_POWER"P3V3_AUX"
CDS_LIB"logical_power";
"A"1;
%"Q_RES"
"1","(-3325,3425)","0","pure_quanta","I110";
;
PACK_TYPE"0402LF"
VALUE"2K"
WATTAGE"1/16W"
MATERIAL"CHIP"
TOLERANCE"1%"
CDS_LIB"pure_quanta"
PART_NUMBER"CS22002FB07"
LOCATION"R75"
$SEC"1"
CDS_SEC"1";
"B"
$PN"2"14;
"A"
$PN"1"2;
%"Q_RES"
"1","(-3325,3625)","0","pure_quanta","I117";
;
MATERIAL"CHIP"
WATTAGE"1/16W"
TOLERANCE"1%"
PACK_TYPE"0402LF"
VALUE"2K"
CDS_LIB"pure_quanta"
PART_NUMBER"CS22002FB07"
LOCATION"R74"
$SEC"1"
CDS_SEC"1";
"B"
$PN"2"15;
"A"
$PN"1"2;
%"Q_RES"
"1","(-3350,3825)","0","pure_quanta","I118";
;
MATERIAL"EMPTY"
PACK_TYPE"0402LF"
WATTAGE"1/16W"
VALUE"1K"
TOLERANCE"1%"
CDS_LIB"pure_quanta"
PART_NUMBER"CS21002FB06"
LOCATION"R73"
$SEC"1"
CDS_SEC"1";
"B"
$PN"2"16;
"A"
$PN"1"2;
%"Q_RES"
"1","(-3325,4450)","0","pure_quanta","I128";
;
PACK_TYPE"0402LF"
MATERIAL"EMPTY"
TOLERANCE"1%"
WATTAGE"1/16W"
VALUE"1K"
CDS_LIB"pure_quanta"
PART_NUMBER"CS21002FB06"
LOCATION"R77"
$SEC"1"
CDS_SEC"1";
"B"
$PN"2"19;
"A"
$PN"1"2;
%"Q_RES"
"1","(-3325,4250)","0","pure_quanta","I129";
;
MATERIAL"CHIP"
PACK_TYPE"0402LF"
TOLERANCE"1%"
WATTAGE"1/16W"
VALUE"2K"
CDS_LIB"pure_quanta"
PART_NUMBER"CS22002FB07"
LOCATION"R78"
$SEC"1"
CDS_SEC"1";
"B"
$PN"2"18;
"A"
$PN"1"2;
%"Q_RES"
"1","(-3325,4050)","0","pure_quanta","I130";
;
MATERIAL"CHIP"
WATTAGE"1/16W"
VALUE"2K"
TOLERANCE"1%"
PACK_TYPE"0402LF"
CDS_LIB"pure_quanta"
PART_NUMBER"CS22002FB07"
LOCATION"R79"
$SEC"1"
CDS_SEC"1";
"B"
$PN"2"17;
"A"
$PN"1"2;
%"Q_RES"
"1","(-200,3625)","0","pure_quanta","I171";
;
MATERIAL"EMPTY"
TOLERANCE"1%"
PACK_TYPE"0402LF"
PART_NUMBER"CS22002FB07"
VALUE"2K"
WATTAGE"1/16W"
CDS_LIB"pure_quanta"
LOCATION"R40"
$SEC"1"
CDS_SEC"1";
"B"
$PN"2"7;
"A"
$PN"1"5;
%"Q_RES"
"1","(-3325,6025)","0","pure_quanta","I175";
;
VALUE"4.7K"
MATERIAL"EMPTY"
PART_NUMBER"CS24702FB06"
PACK_TYPE"0402LF"
WATTAGE"1/16W"
TOLERANCE"1%"
CDS_LIB"pure_quanta"
LOCATION"R44"
$SEC"1"
CDS_SEC"1";
"B"
$PN"2"27;
"A"
$PN"1"2;
%"Q_RES"
"1","(-3325,5825)","0","pure_quanta","I176";
;
VALUE"4.7K"
MATERIAL"CHIP"
CDS_LIB"pure_quanta"
TOLERANCE"1%"
WATTAGE"1/16W"
PACK_TYPE"0402LF"
PART_NUMBER"CS24702FB06"
LOCATION"R45"
$SEC"1"
CDS_SEC"1";
"B"
$PN"2"26;
"A"
$PN"1"2;
%"Q_RES"
"1","(-3300,4625)","0","pure_quanta","I179";
;
VALUE"4.7K"
MATERIAL"CHIP"
CDS_LIB"pure_quanta"
TOLERANCE"1%"
WATTAGE"1/16W"
PACK_TYPE"0402LF"
PART_NUMBER"CS24702FB06"
LOCATION"R68"
$SEC"1"
CDS_SEC"1";
"B"
$PN"2"20;
"A"
$PN"1"2;
%"Q_RES"
"1","(-200,3950)","0","pure_quanta","I181";
;
PACK_TYPE"0402LF"
PART_NUMBER"CS41002FB09"
TOLERANCE"1%"
VALUE"100K"
WATTAGE"1/16W"
MATERIAL"CHIP"
CDS_LIB"pure_quanta"
LOCATION"R66"
$SEC"1"
CDS_SEC"1";
"B"
$PN"2"8;
"A"
$PN"1"5;
%"Q_RES"
"1","(-3375,6975)","0","pure_quanta","I194";
;
VALUE"4.7K"
MATERIAL"EMPTY"
PART_NUMBER"CS24702FB06"
PACK_TYPE"0402LF"
WATTAGE"1/16W"
TOLERANCE"1%"
CDS_LIB"pure_quanta"
LOCATION"R34"
$SEC"1"
CDS_SEC"1";
"B"
$PN"2"29;
"A"
$PN"1"3;
%"UNIVERSAL_GND"
"1","(-825,2925)","0","logical_power","I2";
;
CDS_LIB"logical_power"
HDL_POWER"GND";
"A"5;
%"Q_RES"
"1","(-3325,5625)","0","pure_quanta","I212";
;
VALUE"4.7K"
MATERIAL"CHIP"
CDS_LIB"pure_quanta"
TOLERANCE"1%"
WATTAGE"1/16W"
PACK_TYPE"0402LF"
PART_NUMBER"CS24702FB06"
LOCATION"R163"
$SEC"1"
CDS_SEC"1";
"B"
$PN"2"25;
"A"
$PN"1"2;
%"Q_RES"
"1","(-3325,5425)","0","pure_quanta","I214";
;
VALUE"4.7K"
MATERIAL"CHIP"
CDS_LIB"pure_quanta"
TOLERANCE"1%"
WATTAGE"1/16W"
PACK_TYPE"0402LF"
PART_NUMBER"CS24702FB06"
LOCATION"R101"
$SEC"1"
CDS_SEC"1";
"B"
$PN"2"24;
"A"
$PN"1"2;
%"Q_RES"
"1","(-3325,5025)","0","pure_quanta","I218";
;
VALUE"4.7K"
MATERIAL"CHIP"
CDS_LIB"pure_quanta"
TOLERANCE"1%"
WATTAGE"1/16W"
PACK_TYPE"0402LF"
PART_NUMBER"CS24702FB06"
LOCATION"R161"
$SEC"1"
CDS_SEC"1";
"B"
$PN"2"22;
"A"
$PN"1"2;
%"Q_RES"
"1","(-3325,5225)","0","pure_quanta","I219";
;
VALUE"4.7K"
MATERIAL"CHIP"
CDS_LIB"pure_quanta"
TOLERANCE"1%"
WATTAGE"1/16W"
PACK_TYPE"0402LF"
PART_NUMBER"CS24702FB06"
LOCATION"R103"
$SEC"1"
CDS_SEC"1";
"B"
$PN"2"23;
"A"
$PN"1"2;
%"Q_RES"
"1","(-3325,6225)","0","pure_quanta","I225";
;
VALUE"10K"
MATERIAL"EMPTY"
CDS_LIB"pure_quanta"
TOLERANCE"1%"
WATTAGE"1/16W"
PACK_TYPE"0402LF"
PART_NUMBER"CS31002FB08"
LOCATION"R41"
$SEC"1"
CDS_SEC"1";
"B"
$PN"2"28;
"A"
$PN"1"2;
%"Q_RES"
"1","(-3300,4825)","0","pure_quanta","I227";
;
VALUE"4.7K"
MATERIAL"CHIP"
CDS_LIB"pure_quanta"
TOLERANCE"1%"
WATTAGE"1/16W"
PACK_TYPE"0402LF"
PART_NUMBER"CS24702FB06"
LOCATION"R69"
$SEC"1"
CDS_SEC"1";
"B"
$PN"2"21;
"A"
$PN"1"2;
%"Q_RES"
"1","(2450,5750)","0","pure_quanta","I230";
;
TOLERANCE"1%"
PACK_TYPE"0402LF"
MATERIAL"CHIP"
VALUE"2K"
WATTAGE"1/16W"
CDS_LIB"pure_quanta"
PART_NUMBER"CS22002FB07"
LOCATION"R76"
$SEC"1"
CDS_SEC"1";
"B"
$PN"2"10;
"A"
$PN"1"1;
%"Q_RES"
"1","(2450,5575)","2","pure_quanta","I231";
;
VALUE"0"
TOLERANCE"5%"
MATERIAL"EMPTY"
WATTAGE"1/16W"
PACK_TYPE"0402LF"
CDS_LIB"pure_quanta"
PART_NUMBER"CS00002JB13"
LOCATION"R63"
$SEC"1"
CDS_SEC"1";
"B"
$PN"2"4;
"A"
$PN"1"10;
%"Q_RES"
"1","(2450,6125)","0","pure_quanta","I232";
;
MATERIAL"CHIP"
VALUE"2K"
TOLERANCE"1%"
WATTAGE"1/16W"
PACK_TYPE"0402LF"
CDS_LIB"pure_quanta"
PART_NUMBER"CS22002FB07"
LOCATION"R82"
$SEC"1"
CDS_SEC"1";
"B"
$PN"2"9;
"A"
$PN"1"1;
%"Q_RES"
"1","(2450,5950)","2","pure_quanta","I233";
;
MATERIAL"EMPTY"
VALUE"0"
TOLERANCE"5%"
WATTAGE"1/16W"
PACK_TYPE"0402LF"
CDS_LIB"pure_quanta"
PART_NUMBER"CS00002JB13"
LOCATION"R64"
$SEC"1"
CDS_SEC"1";
"B"
$PN"2"4;
"A"
$PN"1"9;
%"Q_RES"
"1","(-200,3300)","0","pure_quanta","I234";
;
PART_NUMBER"CS41002FB09"
TOLERANCE"1%"
VALUE"100K"
WATTAGE"1/16W"
MATERIAL"CHIP"
PACK_TYPE"0402LF"
CDS_LIB"pure_quanta"
LOCATION"R823"
$SEC"1"
CDS_SEC"1";
"B"
$PN"2"6;
"A"
$PN"1"5;
%"Q_RES"
"1","(-3325,2975)","0","pure_quanta","I241";
;
MATERIAL"EMPTY"
VALUE"4.7K"
CDS_LIB"pure_quanta"
TOLERANCE"1%"
WATTAGE"1/16W"
PACK_TYPE"0402LF"
PART_NUMBER"CS24702FB06"
LOCATION"R828"
$SEC"1"
CDS_SEC"1";
"B"
$PN"2"13;
"A"
$PN"1"2;
%"Q_RES"
"1","(-3325,2750)","0","pure_quanta","I245";
;
MATERIAL"CHIP"
VALUE"4.7K"
CDS_LIB"pure_quanta"
PART_NUMBER"CS24702FB06"
PACK_TYPE"0402LF"
WATTAGE"1/16W"
TOLERANCE"1%"
LOCATION"R81"
$SEC"1"
CDS_SEC"1";
"B"
$PN"2"12;
"A"
$PN"1"2;
%"UNIVERSAL_POWER"
"1","(-3950,7325)","0","logical_power","I254";
;
HDL_POWER"P3V3_RGM"
CDS_LIB"logical_power";
"A"3;
%"Q_RES"
"1","(-3325,2525)","0","pure_quanta","I256";
;
VALUE"4.7K"
MATERIAL"CHIP"
TOLERANCE"1%"
WATTAGE"1/16W"
PACK_TYPE"0402LF"
PART_NUMBER"CS24702FB06"
CDS_LIB"pure_quanta"
LOCATION"R169"
$SEC"1"
CDS_SEC"1";
"B"
$PN"2"11;
"A"
$PN"1"2;
%"VCCAUX15"
"1","(-3950,6575)","0","logical_power","I56";
;
HDL_POWER"P3V3_AUX"
CDS_LIB"logical_power";
"A"2;
%"UNIVERSAL_GND"
"1","(1850,4725)","0","logical_power","I58";
;
CDS_LIB"logical_power"
HDL_POWER"GND";
"A"4;
END.
